(kicad_pcb
	(version 20260206)
	(generator "pcbnew")
	(generator_version "10.0")
	(general
		(thickness 1.6)
		(legacy_teardrops no)
	)
	(paper "A4")
	(title_block
		(title "04192023_DAF0TMB3IC0_F0TG_MB_C_brd_V02_OCP.brd")
		(comment 1 "Grand Teton / footprints 485-491 of 8354")
	)
	(layers
		(0 "F.Cu" signal "TOP")
		(4 "In1.Cu" signal "GND")
		(6 "In2.Cu" signal "IN1")
		(8 "In3.Cu" signal "GND1")
		(10 "In4.Cu" signal "IN2")
		(12 "In5.Cu" signal "GND2")
		(14 "In6.Cu" signal "IN3")
		(16 "In7.Cu" signal "GND3")
		(18 "In8.Cu" signal "VCC")
		(20 "In9.Cu" signal "VCC1")
		(22 "In10.Cu" signal "GND4")
		(24 "In11.Cu" signal "IN4")
		(26 "In12.Cu" signal "GND5")
		(28 "In13.Cu" signal "IN5")
		(30 "In14.Cu" signal "GND6")
		(32 "In15.Cu" signal "IN6")
		(34 "In16.Cu" signal "GND7")
		(2 "B.Cu" signal "BOTTOM")
		(9 "F.Adhes" user "F.Adhesive")
		(11 "B.Adhes" user "B.Adhesive")
		(13 "F.Paste" user "Package Geometry/Pastemask Top")
		(15 "B.Paste" user "Package Geometry/Pastemask Bottom")
		(5 "F.SilkS" user "Ref Des/Silkscreen Top")
		(7 "B.SilkS" user "Ref Des/Silkscreen Bottom")
		(1 "F.Mask" user "Board Geometry/Soldermask Top")
		(3 "B.Mask" user "Board Geometry/Soldermask Bottom")
		(17 "Dwgs.User" user "User.Drawings")
		(19 "Cmts.User" user "User.Comments")
		(21 "Eco1.User" user "User.Eco1")
		(23 "Eco2.User" user "User.Eco2")
		(25 "Edge.Cuts" user "Board Geometry/Outline")
		(27 "Margin" user)
		(31 "F.CrtYd" user "Package Geometry/Place Bound Top")
		(29 "B.CrtYd" user "Package Geometry/Place Bound Bottom")
		(35 "F.Fab" user "Ref Des/Assembly Top")
		(33 "B.Fab" user "Ref Des/Assembly Bottom")
	)
	(footprint ""
		(layer "F.Cu")
		(at 254.592836 -117.51945)
		(property "Reference" "R3728"
			(at 0 0 0)
			(layer "F.SilkS")
			(hide yes)
			(effects
				(font
					(size 1.27 1.27)
				)
			)
		)
		(property "Value" ""
			(at 0 0 0)
			(layer "F.Fab")
			(effects
				(font
					(size 1.27 1.27)
				)
			)
		)
		(duplicate_pad_numbers_are_jumpers no)
		(fp_line
			(start -0.7874 -0.4064)
			(end 0.7874 -0.4064)
			(stroke
				(width 0.1524)
				(type default)
			)
			(layer "F.SilkS")
		)
		(fp_line
			(start -0.7874 0.4064)
			(end -0.7874 -0.4064)
			(stroke
				(width 0.1524)
				(type default)
			)
			(layer "F.SilkS")
		)
		(fp_line
			(start 0.7874 -0.4064)
			(end 0.7874 0.4064)
			(stroke
				(width 0.1524)
				(type default)
			)
			(layer "F.SilkS")
		)
		(fp_line
			(start 0.7874 0.4064)
			(end -0.7874 0.4064)
			(stroke
				(width 0.1524)
				(type default)
			)
			(layer "F.SilkS")
		)
		(fp_line
			(start -0.67945 -0.305054)
			(end -0.12065 -0.305054)
			(stroke
				(width 0.1)
				(type default)
			)
			(layer "F.Fab")
		)
		(fp_line
			(start -0.67945 0.3048)
			(end -0.67945 -0.305054)
			(stroke
				(width 0.1)
				(type default)
			)
			(layer "F.Fab")
		)
		(fp_line
			(start -0.12065 -0.305054)
			(end -0.12065 -0.2794)
			(stroke
				(width 0.1)
				(type default)
			)
			(layer "F.Fab")
		)
		(fp_line
			(start -0.12065 -0.2794)
			(end 0.12065 -0.2794)
			(stroke
				(width 0.1)
				(type default)
			)
			(layer "F.Fab")
		)
		(fp_line
			(start -0.12065 0.2794)
			(end -0.12065 0.3048)
			(stroke
				(width 0.1)
				(type default)
			)
			(layer "F.Fab")
		)
		(fp_line
			(start -0.12065 0.3048)
			(end -0.67945 0.3048)
			(stroke
				(width 0.1)
				(type default)
			)
			(layer "F.Fab")
		)
		(fp_line
			(start 0.120396 0.2794)
			(end -0.12065 0.2794)
			(stroke
				(width 0.1)
				(type default)
			)
			(layer "F.Fab")
		)
		(fp_line
			(start 0.120396 0.3048)
			(end 0.120396 0.2794)
			(stroke
				(width 0.1)
				(type default)
			)
			(layer "F.Fab")
		)
		(fp_line
			(start 0.12065 -0.3048)
			(end 0.67945 -0.3048)
			(stroke
				(width 0.1)
				(type default)
			)
			(layer "F.Fab")
		)
		(fp_line
			(start 0.12065 -0.2794)
			(end 0.12065 -0.3048)
			(stroke
				(width 0.1)
				(type default)
			)
			(layer "F.Fab")
		)
		(fp_line
			(start 0.67945 -0.3048)
			(end 0.67945 0.3048)
			(stroke
				(width 0.1)
				(type default)
			)
			(layer "F.Fab")
		)
		(fp_line
			(start 0.67945 0.3048)
			(end 0.120396 0.3048)
			(stroke
				(width 0.1)
				(type default)
			)
			(layer "F.Fab")
		)
		(pad "1" smd circle
			(at -0.40005 0)
			(size 0 0)
			(layers "F.Cu" "F.Mask" "F.Paste")
			(net "P3V3_AUX")
		)
		(pad "2" smd circle
			(at 0.40005 0)
			(size 0 0)
			(layers "F.Cu" "F.Mask" "F.Paste")
			(net "SMB_LM75_1_3V3AUX_SDA")
		)
	)
	(footprint ""
		(layer "F.Cu")
		(at 455.115676 -401.709128 90)
		(property "Reference" "PR6562"
			(at 0 0 90)
			(layer "F.SilkS")
			(hide yes)
			(effects
				(font
					(size 1.27 1.27)
				)
			)
		)
		(property "Value" ""
			(at 0 0 90)
			(layer "F.Fab")
			(effects
				(font
					(size 1.27 1.27)
				)
			)
		)
		(duplicate_pad_numbers_are_jumpers no)
		(fp_line
			(start 0.7874 -0.4064)
			(end 0.7874 0.4064)
			(stroke
				(width 0.1524)
				(type default)
			)
			(layer "F.SilkS")
		)
		(fp_line
			(start -0.7874 -0.4064)
			(end 0.7874 -0.4064)
			(stroke
				(width 0.1524)
				(type default)
			)
			(layer "F.SilkS")
		)
		(fp_line
			(start 0.7874 0.4064)
			(end -0.7874 0.4064)
			(stroke
				(width 0.1524)
				(type default)
			)
			(layer "F.SilkS")
		)
		(fp_line
			(start -0.7874 0.4064)
			(end -0.7874 -0.4064)
			(stroke
				(width 0.1524)
				(type default)
			)
			(layer "F.SilkS")
		)
		(fp_line
			(start -0.12065 -0.305054)
			(end -0.12065 -0.2794)
			(stroke
				(width 0.1)
				(type default)
			)
			(layer "F.Fab")
		)
		(fp_line
			(start -0.67945 -0.305054)
			(end -0.12065 -0.305054)
			(stroke
				(width 0.1)
				(type default)
			)
			(layer "F.Fab")
		)
		(fp_line
			(start 0.67945 -0.3048)
			(end 0.67945 0.3048)
			(stroke
				(width 0.1)
				(type default)
			)
			(layer "F.Fab")
		)
		(fp_line
			(start 0.12065 -0.3048)
			(end 0.67945 -0.3048)
			(stroke
				(width 0.1)
				(type default)
			)
			(layer "F.Fab")
		)
		(fp_line
			(start 0.12065 -0.2794)
			(end 0.12065 -0.3048)
			(stroke
				(width 0.1)
				(type default)
			)
			(layer "F.Fab")
		)
		(fp_line
			(start -0.12065 -0.2794)
			(end 0.12065 -0.2794)
			(stroke
				(width 0.1)
				(type default)
			)
			(layer "F.Fab")
		)
		(fp_line
			(start 0.120396 0.2794)
			(end -0.12065 0.2794)
			(stroke
				(width 0.1)
				(type default)
			)
			(layer "F.Fab")
		)
		(fp_line
			(start -0.12065 0.2794)
			(end -0.12065 0.3048)
			(stroke
				(width 0.1)
				(type default)
			)
			(layer "F.Fab")
		)
		(fp_line
			(start 0.67945 0.3048)
			(end 0.120396 0.3048)
			(stroke
				(width 0.1)
				(type default)
			)
			(layer "F.Fab")
		)
		(fp_line
			(start 0.120396 0.3048)
			(end 0.120396 0.2794)
			(stroke
				(width 0.1)
				(type default)
			)
			(layer "F.Fab")
		)
		(fp_line
			(start -0.12065 0.3048)
			(end -0.67945 0.3048)
			(stroke
				(width 0.1)
				(type default)
			)
			(layer "F.Fab")
		)
		(fp_line
			(start -0.67945 0.3048)
			(end -0.67945 -0.305054)
			(stroke
				(width 0.1)
				(type default)
			)
			(layer "F.Fab")
		)
		(pad "1" smd circle
			(at -0.40005 0 90)
			(size 0 0)
			(layers "F.Cu" "F.Mask" "F.Paste")
			(net "SW_P0V9_RETIMER_CPU0_BOOT2")
		)
		(pad "2" smd circle
			(at 0.40005 0 90)
			(size 0 0)
			(layers "F.Cu" "F.Mask" "F.Paste")
			(net "SW_P0V9_RETIMER_CPU0_BOOT2_RC")
		)
	)
	(footprint ""
		(layer "F.Cu")
		(at 318.262 -364.617 90)
		(property "Reference" "PR76"
			(at 0 0 90)
			(layer "F.SilkS")
			(hide yes)
			(effects
				(font
					(size 1.27 1.27)
				)
			)
		)
		(property "Value" ""
			(at 0 0 90)
			(layer "F.Fab")
			(effects
				(font
					(size 1.27 1.27)
				)
			)
		)
		(duplicate_pad_numbers_are_jumpers no)
		(fp_line
			(start 0.7874 -0.4064)
			(end 0.7874 0.4064)
			(stroke
				(width 0.1524)
				(type default)
			)
			(layer "F.SilkS")
		)
		(fp_line
			(start -0.7874 -0.4064)
			(end 0.7874 -0.4064)
			(stroke
				(width 0.1524)
				(type default)
			)
			(layer "F.SilkS")
		)
		(fp_line
			(start 0.7874 0.4064)
			(end -0.7874 0.4064)
			(stroke
				(width 0.1524)
				(type default)
			)
			(layer "F.SilkS")
		)
		(fp_line
			(start -0.7874 0.4064)
			(end -0.7874 -0.4064)
			(stroke
				(width 0.1524)
				(type default)
			)
			(layer "F.SilkS")
		)
		(fp_line
			(start -0.12065 -0.305054)
			(end -0.12065 -0.2794)
			(stroke
				(width 0.1)
				(type default)
			)
			(layer "F.Fab")
		)
		(fp_line
			(start -0.67945 -0.305054)
			(end -0.12065 -0.305054)
			(stroke
				(width 0.1)
				(type default)
			)
			(layer "F.Fab")
		)
		(fp_line
			(start 0.67945 -0.3048)
			(end 0.67945 0.3048)
			(stroke
				(width 0.1)
				(type default)
			)
			(layer "F.Fab")
		)
		(fp_line
			(start 0.12065 -0.3048)
			(end 0.67945 -0.3048)
			(stroke
				(width 0.1)
				(type default)
			)
			(layer "F.Fab")
		)
		(fp_line
			(start 0.12065 -0.2794)
			(end 0.12065 -0.3048)
			(stroke
				(width 0.1)
				(type default)
			)
			(layer "F.Fab")
		)
		(fp_line
			(start -0.12065 -0.2794)
			(end 0.12065 -0.2794)
			(stroke
				(width 0.1)
				(type default)
			)
			(layer "F.Fab")
		)
		(fp_line
			(start 0.120396 0.2794)
			(end -0.12065 0.2794)
			(stroke
				(width 0.1)
				(type default)
			)
			(layer "F.Fab")
		)
		(fp_line
			(start -0.12065 0.2794)
			(end -0.12065 0.3048)
			(stroke
				(width 0.1)
				(type default)
			)
			(layer "F.Fab")
		)
		(fp_line
			(start 0.67945 0.3048)
			(end 0.120396 0.3048)
			(stroke
				(width 0.1)
				(type default)
			)
			(layer "F.Fab")
		)
		(fp_line
			(start 0.120396 0.3048)
			(end 0.120396 0.2794)
			(stroke
				(width 0.1)
				(type default)
			)
			(layer "F.Fab")
		)
		(fp_line
			(start -0.12065 0.3048)
			(end -0.67945 0.3048)
			(stroke
				(width 0.1)
				(type default)
			)
			(layer "F.Fab")
		)
		(fp_line
			(start -0.67945 0.3048)
			(end -0.67945 -0.305054)
			(stroke
				(width 0.1)
				(type default)
			)
			(layer "F.Fab")
		)
		(pad "1" smd circle
			(at -0.40005 0 90)
			(size 0 0)
			(layers "F.Cu" "F.Mask" "F.Paste")
			(net "PVDDCR_CPU1_P0_VCC")
		)
		(pad "2" smd circle
			(at 0.40005 0 90)
			(size 0 0)
			(layers "F.Cu" "F.Mask" "F.Paste")
			(net "P3V3_AUX")
		)
	)
	(footprint ""
		(layer "F.Cu")
		(at 34.325306 19.444716 -90)
		(property "Reference" "U26_BP"
			(at 0 0 270)
			(layer "F.SilkS")
			(hide yes)
			(effects
				(font
					(size 1.27 1.27)
				)
			)
		)
		(property "Value" ""
			(at 0 0 270)
			(layer "F.Fab")
			(effects
				(font
					(size 1.27 1.27)
				)
			)
		)
		(duplicate_pad_numbers_are_jumpers no)
		(pad "1" smd circle
			(at 0 0 270)
			(size 0.762 0.762)
			(layers "F.Cu" "F.Mask" "F.Paste")
			(net "Net_10787")
		)
	)
	(footprint ""
		(layer "F.Cu")
		(at 109.165136 -123.604274 -90)
		(property "Reference" "Q27"
			(at -0.13208 1.599438 90)
			(unlocked yes)
			(layer "F.SilkS")
			(effects
				(font
					(size 0.7874 0.5842)
					(thickness 0.1524)
				)
			)
		)
		(property "Value" ""
			(at 0 0 270)
			(layer "F.Fab")
			(effects
				(font
					(size 1.27 1.27)
				)
			)
		)
		(duplicate_pad_numbers_are_jumpers no)
		(fp_line
			(start -1.7018 1.100074)
			(end -1.7018 -1.100074)
			(stroke
				(width 0.1524)
				(type default)
			)
			(layer "F.SilkS")
		)
		(fp_line
			(start 1.7018 1.100074)
			(end -1.7018 1.100074)
			(stroke
				(width 0.1524)
				(type default)
			)
			(layer "F.SilkS")
		)
		(fp_line
			(start -1.7018 -1.100074)
			(end 1.7018 -1.100074)
			(stroke
				(width 0.1524)
				(type default)
			)
			(layer "F.SilkS")
		)
		(fp_line
			(start 1.7018 -1.100074)
			(end 1.7018 1.100074)
			(stroke
				(width 0.1524)
				(type default)
			)
			(layer "F.SilkS")
		)
		(fp_poly
			(pts
				(xy -2.313686 -0.705866) (xy -2.867406 -0.409194) (xy -2.867406 -1.034034)
			)
			(stroke
				(width 0)
				(type default)
			)
			(fill yes)
			(layer "F.SilkS")
		)
		(fp_line
			(start -0.670052 1.100074)
			(end -0.670052 0.8001)
			(stroke
				(width 0.1)
				(type default)
			)
			(layer "F.Fab")
		)
		(fp_line
			(start 0.670052 1.100074)
			(end -0.670052 1.100074)
			(stroke
				(width 0.1)
				(type default)
			)
			(layer "F.Fab")
		)
		(fp_line
			(start -1.100074 0.8001)
			(end -1.100074 -0.8001)
			(stroke
				(width 0.1)
				(type default)
			)
			(layer "F.Fab")
		)
		(fp_line
			(start -0.670052 0.8001)
			(end -1.100074 0.8001)
			(stroke
				(width 0.1)
				(type default)
			)
			(layer "F.Fab")
		)
		(fp_line
			(start -0.670052 0.8001)
			(end -0.670052 -0.8001)
			(stroke
				(width 0.1)
				(type default)
			)
			(layer "F.Fab")
		)
		(fp_line
			(start 0.670052 0.8001)
			(end 0.670052 1.100074)
			(stroke
				(width 0.1)
				(type default)
			)
			(layer "F.Fab")
		)
		(fp_line
			(start 1.100074 0.8001)
			(end 0.670052 0.8001)
			(stroke
				(width 0.1)
				(type default)
			)
			(layer "F.Fab")
		)
		(fp_line
			(start -1.100074 -0.8001)
			(end -0.670052 -0.8001)
			(stroke
				(width 0.1)
				(type default)
			)
			(layer "F.Fab")
		)
		(fp_line
			(start -0.670052 -0.8001)
			(end -0.670052 -1.100074)
			(stroke
				(width 0.1)
				(type default)
			)
			(layer "F.Fab")
		)
		(fp_line
			(start 0.670052 -0.8001)
			(end 0.670052 0.8001)
			(stroke
				(width 0.1)
				(type default)
			)
			(layer "F.Fab")
		)
		(fp_line
			(start 0.670052 -0.8001)
			(end 1.100074 -0.8001)
			(stroke
				(width 0.1)
				(type default)
			)
			(layer "F.Fab")
		)
		(fp_line
			(start 1.100074 -0.8001)
			(end 1.100074 0.8001)
			(stroke
				(width 0.1)
				(type default)
			)
			(layer "F.Fab")
		)
		(fp_line
			(start -0.670052 -1.100074)
			(end 0.670052 -1.100074)
			(stroke
				(width 0.1)
				(type default)
			)
			(layer "F.Fab")
		)
		(fp_line
			(start 0.670052 -1.100074)
			(end 0.670052 -0.8001)
			(stroke
				(width 0.1)
				(type default)
			)
			(layer "F.Fab")
		)
		(fp_poly
			(pts
				(xy -2.33172 -0.338328) (xy -2.33172 -0.963168) (xy -1.778 -0.635)
			)
			(stroke
				(width 0)
				(type default)
			)
			(fill yes)
			(layer "F.Fab")
		)
		(pad "1" smd rect
			(at -0.937514 -0.649986)
			(size 0.3048 1.2446)
			(layers "F.Cu" "F.Mask" "F.Paste")
			(net "GND")
		)
		(pad "2" smd rect
			(at -0.937514 0)
			(size 0.3048 1.2446)
			(layers "F.Cu" "F.Mask" "F.Paste")
			(net "PWRGD_P3V3_EN")
		)
		(pad "3" smd rect
			(at -0.937514 0.649986)
			(size 0.3048 1.2446)
			(layers "F.Cu" "F.Mask" "F.Paste")
			(net "PWRGD_P3V3_R1")
		)
		(pad "4" smd rect
			(at 0.937514 0.649986)
			(size 0.3048 1.2446)
			(layers "F.Cu" "F.Mask" "F.Paste")
			(net "GND")
		)
		(pad "5" smd rect
			(at 0.937514 0)
			(size 0.3048 1.2446)
			(layers "F.Cu" "F.Mask" "F.Paste")
			(net "PWRGD_P3V3_EN_N")
		)
		(pad "6" smd rect
			(at 0.937514 -0.649986)
			(size 0.3048 1.2446)
			(layers "F.Cu" "F.Mask" "F.Paste")
			(net "PWRGD_P3V3_EN_N")
		)
	)
	(footprint ""
		(layer "F.Cu")
		(at 123.871736 -59.182)
		(property "Reference" "R1745"
			(at 0 0 0)
			(layer "F.SilkS")
			(hide yes)
			(effects
				(font
					(size 1.27 1.27)
				)
			)
		)
		(property "Value" ""
			(at 0 0 0)
			(layer "F.Fab")
			(effects
				(font
					(size 1.27 1.27)
				)
			)
		)
		(duplicate_pad_numbers_are_jumpers no)
		(fp_line
			(start -0.7874 -0.4064)
			(end 0.7874 -0.4064)
			(stroke
				(width 0.1524)
				(type default)
			)
			(layer "F.SilkS")
		)
		(fp_line
			(start -0.7874 0.4064)
			(end -0.7874 -0.4064)
			(stroke
				(width 0.1524)
				(type default)
			)
			(layer "F.SilkS")
		)
		(fp_line
			(start 0.7874 -0.4064)
			(end 0.7874 0.4064)
			(stroke
				(width 0.1524)
				(type default)
			)
			(layer "F.SilkS")
		)
		(fp_line
			(start 0.7874 0.4064)
			(end -0.7874 0.4064)
			(stroke
				(width 0.1524)
				(type default)
			)
			(layer "F.SilkS")
		)
		(fp_line
			(start -0.67945 -0.305054)
			(end -0.12065 -0.305054)
			(stroke
				(width 0.1)
				(type default)
			)
			(layer "F.Fab")
		)
		(fp_line
			(start -0.67945 0.3048)
			(end -0.67945 -0.305054)
			(stroke
				(width 0.1)
				(type default)
			)
			(layer "F.Fab")
		)
		(fp_line
			(start -0.12065 -0.305054)
			(end -0.12065 -0.2794)
			(stroke
				(width 0.1)
				(type default)
			)
			(layer "F.Fab")
		)
		(fp_line
			(start -0.12065 -0.2794)
			(end 0.12065 -0.2794)
			(stroke
				(width 0.1)
				(type default)
			)
			(layer "F.Fab")
		)
		(fp_line
			(start -0.12065 0.2794)
			(end -0.12065 0.3048)
			(stroke
				(width 0.1)
				(type default)
			)
			(layer "F.Fab")
		)
		(fp_line
			(start -0.12065 0.3048)
			(end -0.67945 0.3048)
			(stroke
				(width 0.1)
				(type default)
			)
			(layer "F.Fab")
		)
		(fp_line
			(start 0.120396 0.2794)
			(end -0.12065 0.2794)
			(stroke
				(width 0.1)
				(type default)
			)
			(layer "F.Fab")
		)
		(fp_line
			(start 0.120396 0.3048)
			(end 0.120396 0.2794)
			(stroke
				(width 0.1)
				(type default)
			)
			(layer "F.Fab")
		)
		(fp_line
			(start 0.12065 -0.3048)
			(end 0.67945 -0.3048)
			(stroke
				(width 0.1)
				(type default)
			)
			(layer "F.Fab")
		)
		(fp_line
			(start 0.12065 -0.2794)
			(end 0.12065 -0.3048)
			(stroke
				(width 0.1)
				(type default)
			)
			(layer "F.Fab")
		)
		(fp_line
			(start 0.67945 -0.3048)
			(end 0.67945 0.3048)
			(stroke
				(width 0.1)
				(type default)
			)
			(layer "F.Fab")
		)
		(fp_line
			(start 0.67945 0.3048)
			(end 0.120396 0.3048)
			(stroke
				(width 0.1)
				(type default)
			)
			(layer "F.Fab")
		)
		(pad "1" smd circle
			(at -0.40005 0)
			(size 0 0)
			(layers "F.Cu" "F.Mask" "F.Paste")
			(net "P3V3_AUX")
		)
		(pad "2" smd circle
			(at 0.40005 0)
			(size 0 0)
			(layers "F.Cu" "F.Mask" "F.Paste")
			(net "JTAG_SCM_MUX_TDO")
		)
	)
	(footprint ""
		(layer "F.Cu")
		(at 57.697878 -181.84241)
		(property "Reference" "TP17"
			(at -2.071878 1.52908 0)
			(unlocked yes)
			(layer "F.SilkS")
			(effects
				(font
					(size 0.7874 0.5842)
					(thickness 0.1524)
				)
				(justify left)
			)
		)
		(property "Value" ""
			(at 0 0 0)
			(layer "F.Fab")
			(effects
				(font
					(size 1.27 1.27)
				)
			)
		)
		(duplicate_pad_numbers_are_jumpers no)
		(pad "1" smd circle
			(at 0 0)
			(size 0.762 0.762)
			(layers "F.Cu" "F.Mask" "F.Paste")
			(net "VSENSE_PVDDCR_CPU0_P1_DP")
		)
	)
)
